(kicad_pcb
	(version 20260206)
	(generator "pcbnew")
	(generator_version "10.0")
	(general
		(thickness 1.6)
		(legacy_teardrops no)
	)
	(paper "A4")
	(title_block
		(title "v1-pdb — T6M_PDB_D_0927_0900.brd")
		(comment 1 "Open CloudServer (Microsoft) / footprints 125-129 of 321")
	)
	(layers
		(0 "F.Cu" signal "TOP")
		(4 "In1.Cu" signal "GND")
		(6 "In2.Cu" signal "IN1")
		(8 "In3.Cu" signal "VCC")
		(10 "In4.Cu" signal "VCC1")
		(12 "In5.Cu" signal "IN2")
		(14 "In6.Cu" signal "GND1")
		(2 "B.Cu" signal "BOTTOM")
		(9 "F.Adhes" user "F.Adhesive")
		(11 "B.Adhes" user "B.Adhesive")
		(13 "F.Paste" user "Package Geometry/Pastemask Top")
		(15 "B.Paste" user "Package Geometry/Pastemask Bottom")
		(5 "F.SilkS" user "Ref Des/Silkscreen Top")
		(7 "B.SilkS" user "Ref Des/Silkscreen Bottom")
		(1 "F.Mask" user "Board Geometry/Soldermask Top")
		(3 "B.Mask" user "Board Geometry/Soldermask Bottom")
		(17 "Dwgs.User" user "User.Drawings")
		(19 "Cmts.User" user "User.Comments")
		(21 "Eco1.User" user "User.Eco1")
		(23 "Eco2.User" user "User.Eco2")
		(25 "Edge.Cuts" user "Board Geometry/Outline")
		(27 "Margin" user)
		(31 "F.CrtYd" user "Package Geometry/Place Bound Top")
		(29 "B.CrtYd" user "Package Geometry/Place Bound Bottom")
		(35 "F.Fab" user "Ref Des/Assembly Top")
		(33 "B.Fab" user "Ref Des/Assembly Bottom")
	)
	(footprint ""
		(layer "F.Cu")
		(at 49.873662 -374.437148 180)
		(property "Reference" "CE17"
			(at -5.288534 -1.081024 0)
			(unlocked yes)
			(layer "F.SilkS")
			(effects
				(font
					(size 0.7874 0.5842)
					(thickness 0.1524)
				)
				(justify left)
			)
		)
		(property "Value" ""
			(at 0 0 180)
			(layer "F.Fab")
			(effects
				(font
					(size 1.27 1.27)
				)
			)
		)
		(duplicate_pad_numbers_are_jumpers no)
		(fp_line
			(start 0 -4.2672)
			(end 0 4.2672)
			(stroke
				(width 0.1524)
				(type default)
			)
			(layer "F.SilkS")
		)
		(fp_circle
			(center 0 0)
			(end -4.2672 0)
			(stroke
				(width 0.1524)
				(type default)
			)
			(fill no)
			(layer "F.SilkS")
		)
		(fp_poly
			(pts
				(arc
					(start 0 -4.2672)
					(mid 4.2672 0)
					(end 0 4.2672)
				)
			)
			(stroke
				(width 0)
				(type default)
			)
			(fill yes)
			(layer "F.SilkS")
		)
		(fp_poly
			(pts
				(xy -2.5146 -0.762) (xy -0.9906 -0.762) (xy -0.9906 0.762) (xy -2.5146 0.762)
			)
			(stroke
				(width 0)
				(type default)
			)
			(fill no)
			(layer "B.CrtYd")
		)
		(fp_poly
			(pts
				(arc
					(start 1.7526 0.762)
					(mid 2.291415 -0.538815)
					(end 0.9906 0)
				)
				(arc
					(start 0.9906 0.0254)
					(mid 1.206345 0.546255)
					(end 1.7272 0.762)
				)
			)
			(stroke
				(width 0)
				(type default)
			)
			(fill no)
			(layer "B.CrtYd")
		)
		(fp_poly
			(pts
				(arc
					(start -4.2672 0)
					(mid 4.2672 0)
					(end -4.2672 0)
				)
			)
			(stroke
				(width 0)
				(type default)
			)
			(fill no)
			(layer "F.CrtYd")
		)
		(fp_circle
			(center 0 0)
			(end -4.2672 0)
			(stroke
				(width 0.1)
				(type default)
			)
			(fill no)
			(layer "F.Fab")
		)
		(fp_text user "+"
			(at -4.943602 1.518412 180)
			(unlocked yes)
			(layer "F.SilkS")
			(effects
				(font
					(size 0.7874 0.5842)
					(thickness 0.1524)
				)
				(justify left)
			)
		)
		(fp_text user "+"
			(at -5.6642 -0.34925 180)
			(unlocked yes)
			(layer "F.Fab")
			(effects
				(font
					(size 1.905 1.4224)
					(thickness 0.000001)
				)
				(justify left)
			)
		)
		(pad "1" thru_hole rect
			(at -1.75006 0 180)
			(size 1.397 1.397)
			(drill 0.9144)
			(layers "*.Cu" "*.Mask")
			(remove_unused_layers no)
			(net "P12V")
			(clearance 0.0127)
			(thermal_gap 0.0127)
			(padstack
				(mode front_inner_back)
				(layer "Inner"
					(shape circle)
					(size 1.397 1.397)
					(clearance 0.0127)
				)
				(layer "B.Cu"
					(shape rect)
					(size 1.397 1.397)
					(clearance 0.0127)
				)
			)
		)
		(pad "2" thru_hole circle
			(at 1.75006 0 180)
			(size 1.397 1.397)
			(drill 0.9144)
			(layers "*.Cu" "*.Mask")
			(remove_unused_layers no)
			(net "GND")
			(clearance 0.0127)
			(thermal_gap 0.0127)
		)
	)
	(footprint ""
		(layer "F.Cu")
		(at 13.39469 -8.878062 180)
		(property "Reference" "J19"
			(at 6.82117 14.260576 0)
			(unlocked yes)
			(layer "F.SilkS")
			(effects
				(font
					(size 0.7874 0.5842)
					(thickness 0.1524)
				)
				(justify left)
			)
		)
		(property "Value" ""
			(at 0 0 180)
			(layer "F.Fab")
			(effects
				(font
					(size 1.27 1.27)
				)
			)
		)
		(duplicate_pad_numbers_are_jumpers no)
		(fp_line
			(start 12.260072 12.830048)
			(end -3.370072 12.830048)
			(stroke
				(width 0.1524)
				(type default)
			)
			(layer "F.SilkS")
		)
		(fp_line
			(start 12.260072 -3.81)
			(end 12.260072 12.830048)
			(stroke
				(width 0.1524)
				(type default)
			)
			(layer "F.SilkS")
		)
		(fp_line
			(start -3.370072 12.830048)
			(end -3.370072 -3.81)
			(stroke
				(width 0.1524)
				(type default)
			)
			(layer "F.SilkS")
		)
		(fp_line
			(start -3.370072 -3.81)
			(end 12.260072 -3.81)
			(stroke
				(width 0.1524)
				(type default)
			)
			(layer "F.SilkS")
		)
		(fp_poly
			(pts
				(xy -3.576828 0) (xy -5.0038 0.713486) (xy -5.0038 -0.713486)
			)
			(stroke
				(width 0)
				(type default)
			)
			(fill yes)
			(layer "F.SilkS")
		)
		(fp_poly
			(pts
				(xy -0.762 0.762) (xy 8.382 0.762) (xy 8.382 -1.8034) (xy 9.652 -1.8034) (xy 9.652 -3.302) (xy 0.508 -3.302)
				(xy 0.508 -0.762) (xy -0.762 -0.762)
			)
			(stroke
				(width 0)
				(type default)
			)
			(fill no)
			(layer "B.CrtYd")
		)
		(fp_poly
			(pts
				(arc
					(start 8.2296 6.35)
					(mid 12.0904 6.35)
					(end 8.2296 6.35)
				)
			)
			(stroke
				(width 0)
				(type default)
			)
			(fill no)
			(layer "B.CrtYd")
		)
		(fp_poly
			(pts
				(arc
					(start -3.2004 6.35)
					(mid 0.6604 6.35)
					(end -3.2004 6.35)
				)
			)
			(stroke
				(width 0)
				(type default)
			)
			(fill no)
			(layer "B.CrtYd")
		)
		(fp_poly
			(pts
				(xy -3.370072 12.830048) (xy 12.260072 12.830048) (xy 12.260072 -3.81) (xy -3.370072 -3.81)
			)
			(stroke
				(width 0)
				(type default)
			)
			(fill no)
			(layer "F.CrtYd")
		)
		(fp_line
			(start 12.260072 12.830048)
			(end -3.370072 12.830048)
			(stroke
				(width 0.1)
				(type default)
			)
			(layer "F.Fab")
		)
		(fp_line
			(start 12.260072 -3.81)
			(end 12.260072 12.830048)
			(stroke
				(width 0.1)
				(type default)
			)
			(layer "F.Fab")
		)
		(fp_line
			(start -3.370072 12.830048)
			(end -3.370072 -3.81)
			(stroke
				(width 0.1)
				(type default)
			)
			(layer "F.Fab")
		)
		(fp_line
			(start -3.370072 -3.81)
			(end 12.260072 -3.81)
			(stroke
				(width 0.1)
				(type default)
			)
			(layer "F.Fab")
		)
		(fp_poly
			(pts
				(xy -3.576828 0) (xy -5.0038 0.713486) (xy -5.0038 -0.713486)
			)
			(stroke
				(width 0)
				(type default)
			)
			(fill yes)
			(layer "F.Fab")
		)
		(fp_text user "7"
			(at 12.7762 0.249174 0)
			(unlocked yes)
			(layer "F.SilkS")
			(effects
				(font
					(size 0.7874 0.5842)
					(thickness 0.1524)
				)
			)
		)
		(fp_text user "8"
			(at 12.7762 -2.214626 0)
			(unlocked yes)
			(layer "F.SilkS")
			(effects
				(font
					(size 0.7874 0.5842)
					(thickness 0.1524)
				)
			)
		)
		(fp_text user "1"
			(at -3.878072 -0.92329 0)
			(unlocked yes)
			(layer "F.SilkS")
			(effects
				(font
					(size 0.7874 0.5842)
					(thickness 0.1524)
				)
			)
		)
		(fp_text user "2"
			(at -3.928872 -2.42189 0)
			(unlocked yes)
			(layer "F.SilkS")
			(effects
				(font
					(size 0.7874 0.5842)
					(thickness 0.1524)
				)
			)
		)
		(fp_text user "8"
			(at 10.050526 -2.129028 0)
			(unlocked yes)
			(layer "B.SilkS")
			(effects
				(font
					(size 0.7874 0.5842)
					(thickness 0.1524)
				)
				(justify mirror)
			)
		)
		(fp_text user "7"
			(at 8.780526 0.512572 0)
			(unlocked yes)
			(layer "B.SilkS")
			(effects
				(font
					(size 0.7874 0.5842)
					(thickness 0.1524)
				)
				(justify mirror)
			)
		)
		(fp_text user "2"
			(at -0.033274 -2.306828 0)
			(unlocked yes)
			(layer "B.SilkS")
			(effects
				(font
					(size 0.7874 0.5842)
					(thickness 0.1524)
				)
				(justify mirror)
			)
		)
		(fp_text user "1"
			(at -1.328674 0.360172 0)
			(unlocked yes)
			(layer "B.SilkS")
			(effects
				(font
					(size 0.7874 0.5842)
					(thickness 0.1524)
				)
				(justify mirror)
			)
		)
		(fp_text user "8"
			(at 10.0838 -2.403348 180)
			(unlocked yes)
			(layer "B.Fab")
			(effects
				(font
					(size 0.7874 0.5842)
					(thickness 0.000001)
				)
				(justify mirror)
			)
		)
		(fp_text user "7"
			(at 8.8138 0.238252 180)
			(unlocked yes)
			(layer "B.Fab")
			(effects
				(font
					(size 0.7874 0.5842)
					(thickness 0.000001)
				)
				(justify mirror)
			)
		)
		(fp_text user "2"
			(at 0 -2.581148 180)
			(unlocked yes)
			(layer "B.Fab")
			(effects
				(font
					(size 0.7874 0.5842)
					(thickness 0.000001)
				)
				(justify mirror)
			)
		)
		(fp_text user "1"
			(at -1.2954 0.085852 180)
			(unlocked yes)
			(layer "B.Fab")
			(effects
				(font
					(size 0.7874 0.5842)
					(thickness 0.000001)
				)
				(justify mirror)
			)
		)
		(fp_text user "7"
			(at 12.7762 -0.091948 180)
			(unlocked yes)
			(layer "F.Fab")
			(effects
				(font
					(size 0.7874 0.5842)
					(thickness 0.000001)
				)
			)
		)
		(fp_text user "8"
			(at 12.7762 -2.555748 180)
			(unlocked yes)
			(layer "F.Fab")
			(effects
				(font
					(size 0.7874 0.5842)
					(thickness 0.000001)
				)
			)
		)
		(fp_text user "1"
			(at -3.9116 -0.930148 180)
			(unlocked yes)
			(layer "F.Fab")
			(effects
				(font
					(size 0.7874 0.5842)
					(thickness 0.000001)
				)
			)
		)
		(fp_text user "2"
			(at -3.9624 -2.428748 180)
			(unlocked yes)
			(layer "F.Fab")
			(effects
				(font
					(size 0.7874 0.5842)
					(thickness 0.000001)
				)
			)
		)
		(pad "" np_thru_hole circle
			(at -1.27 6.35 180)
			(size 3.3528 3.3528)
			(drill 3.3528)
			(layers "*.Cu" "*.Mask")
			(clearance 0.381)
			(thermal_gap 0.381)
		)
		(pad "" np_thru_hole circle
			(at 10.16 6.35 180)
			(size 3.3528 3.3528)
			(drill 3.3528)
			(layers "*.Cu" "*.Mask")
			(clearance 0.381)
			(thermal_gap 0.381)
		)
		(pad "1" thru_hole rect
			(at 0 0 180)
			(size 1.397 1.397)
			(drill 0.9906)
			(layers "*.Cu" "*.Mask")
			(remove_unused_layers no)
			(net "UART_RTS_P1_L_N")
			(clearance 0.0508)
			(thermal_gap 0.0508)
			(padstack
				(mode front_inner_back)
				(layer "Inner"
					(shape circle)
					(size 1.397 1.397)
					(clearance 0.0508)
				)
				(layer "B.Cu"
					(shape rect)
					(size 1.397 1.397)
					(clearance 0.0508)
				)
			)
		)
		(pad "2" thru_hole circle
			(at 1.27 -2.54 180)
			(size 1.397 1.397)
			(drill 0.9906)
			(layers "*.Cu" "*.Mask")
			(remove_unused_layers no)
			(net "UART_DSR_P1_L_N")
			(clearance 0.0508)
			(thermal_gap 0.0508)
		)
		(pad "3" thru_hole circle
			(at 2.54 0 180)
			(size 1.397 1.397)
			(drill 0.9906)
			(layers "*.Cu" "*.Mask")
			(remove_unused_layers no)
			(net "UART_RX_P1_L")
			(clearance 0.0508)
			(thermal_gap 0.0508)
		)
		(pad "4" thru_hole circle
			(at 3.81 -2.54 180)
			(size 1.397 1.397)
			(drill 0.9906)
			(layers "*.Cu" "*.Mask")
			(remove_unused_layers no)
			(net "GND")
			(clearance 0.0508)
			(thermal_gap 0.0508)
		)
		(pad "5" thru_hole circle
			(at 5.08 0 180)
			(size 1.397 1.397)
			(drill 0.9906)
			(layers "*.Cu" "*.Mask")
			(remove_unused_layers no)
			(net "GND")
			(clearance 0.0508)
			(thermal_gap 0.0508)
		)
		(pad "6" thru_hole circle
			(at 6.35 -2.54 180)
			(size 1.397 1.397)
			(drill 0.9906)
			(layers "*.Cu" "*.Mask")
			(remove_unused_layers no)
			(net "UART_TX_P1_L")
			(clearance 0.0508)
			(thermal_gap 0.0508)
		)
		(pad "7" thru_hole circle
			(at 7.62 0 180)
			(size 1.397 1.397)
			(drill 0.9906)
			(layers "*.Cu" "*.Mask")
			(remove_unused_layers no)
			(net "UART_DTR_P1_L_N")
			(clearance 0.0508)
			(thermal_gap 0.0508)
		)
		(pad "8" thru_hole circle
			(at 8.89 -2.54 180)
			(size 1.397 1.397)
			(drill 0.9906)
			(layers "*.Cu" "*.Mask")
			(remove_unused_layers no)
			(net "UART_CTS_P1_L_N")
			(clearance 0.0508)
			(thermal_gap 0.0508)
		)
		(zone
			(layers "F.Cu" "B.Cu" "In1.Cu" "In2.Cu" "In3.Cu" "In4.Cu" "In5.Cu" "In6.Cu")
			(hatch none 0.5)
			(connect_pads
				(clearance 0)
			)
			(min_thickness 0.25)
			(keepout
				(tracks not_allowed)
				(vias allowed)
				(pads allowed)
				(copperpour not_allowed)
				(footprints allowed)
			)
			(placement
				(enabled no)
				(sheetname "")
			)
			(fill
				(thermal_gap 0.5)
				(thermal_bridge_width 0.5)
				(island_removal_mode 0)
			)
			(polygon
				(pts
					(arc
						(start 5.31749 -15.228062)
						(mid 1.15189 -15.228062)
						(end 5.31749 -15.228062)
					)
				)
			)
		)
		(zone
			(layers "F.Cu" "B.Cu" "In1.Cu" "In2.Cu" "In3.Cu" "In4.Cu" "In5.Cu" "In6.Cu")
			(hatch none 0.5)
			(connect_pads
				(clearance 0)
			)
			(min_thickness 0.25)
			(keepout
				(tracks not_allowed)
				(vias allowed)
				(pads allowed)
				(copperpour not_allowed)
				(footprints allowed)
			)
			(placement
				(enabled no)
				(sheetname "")
			)
			(fill
				(thermal_gap 0.5)
				(thermal_bridge_width 0.5)
				(island_removal_mode 0)
			)
			(polygon
				(pts
					(arc
						(start 16.74749 -15.228062)
						(mid 12.58189 -15.228062)
						(end 16.74749 -15.228062)
					)
				)
			)
		)
	)
	(footprint ""
		(layer "F.Cu")
		(at 46.385734 -244.518434 180)
		(property "Reference" "R91"
			(at 4.322064 -0.051816 0)
			(unlocked yes)
			(layer "F.SilkS")
			(effects
				(font
					(size 0.7874 0.5842)
					(thickness 0.1524)
				)
				(justify left)
			)
		)
		(property "Value" ""
			(at 0 0 180)
			(layer "F.Fab")
			(effects
				(font
					(size 1.27 1.27)
				)
			)
		)
		(duplicate_pad_numbers_are_jumpers no)
		(fp_line
			(start 0.7874 0.4064)
			(end -0.7874 0.4064)
			(stroke
				(width 0.1524)
				(type default)
			)
			(layer "F.SilkS")
		)
		(fp_line
			(start 0.7874 -0.4064)
			(end 0.7874 0.4064)
			(stroke
				(width 0.1524)
				(type default)
			)
			(layer "F.SilkS")
		)
		(fp_line
			(start -0.7874 0.4064)
			(end -0.7874 -0.4064)
			(stroke
				(width 0.1524)
				(type default)
			)
			(layer "F.SilkS")
		)
		(fp_line
			(start -0.7874 -0.4064)
			(end 0.7874 -0.4064)
			(stroke
				(width 0.1524)
				(type default)
			)
			(layer "F.SilkS")
		)
		(fp_poly
			(pts
				(xy -0.508 0.2794) (xy -0.508 0.2286) (xy -0.635 0.2286) (xy -0.635 -0.254) (xy -0.5334 -0.254)
				(xy -0.5334 -0.2794) (xy 0.5334 -0.2794) (xy 0.5334 -0.254) (xy 0.635 -0.254) (xy 0.635 0.254) (xy 0.5334 0.254)
				(xy 0.5334 0.2794)
			)
			(stroke
				(width 0)
				(type default)
			)
			(fill no)
			(layer "F.CrtYd")
		)
		(pad "1" smd rect
			(at 0.40005 0 180)
			(size 0.4572 0.508)
			(layers "F.Cu" "F.Mask" "F.Paste")
			(net "PSU2_REMOTE_R_N")
		)
		(pad "2" smd rect
			(at -0.40005 0 180)
			(size 0.4572 0.508)
			(layers "F.Cu" "F.Mask" "F.Paste")
			(net "GND")
		)
	)
	(footprint ""
		(layer "F.Cu")
		(at 77.999844 -78.299818)
		(property "Reference" "H14"
			(at -3.678174 -4.056888 0)
			(unlocked yes)
			(layer "F.SilkS")
			(effects
				(font
					(size 0.7874 0.5842)
					(thickness 0.1524)
				)
				(justify left)
			)
		)
		(property "Value" ""
			(at 0 0 0)
			(layer "F.Fab")
			(effects
				(font
					(size 1.27 1.27)
				)
			)
		)
		(duplicate_pad_numbers_are_jumpers no)
		(fp_circle
			(center 0 0)
			(end 3.4163 0)
			(stroke
				(width 0.1524)
				(type default)
			)
			(fill no)
			(layer "F.SilkS")
		)
		(fp_circle
			(center 0 0)
			(end 3.41884 0)
			(stroke
				(width 0.1524)
				(type default)
			)
			(fill no)
			(layer "B.SilkS")
		)
		(fp_poly
			(pts
				(arc
					(start 2.8575 0)
					(mid -2.8575 0)
					(end 2.8575 0)
				)
			)
			(stroke
				(width 0)
				(type default)
			)
			(fill no)
			(layer "B.CrtYd")
		)
		(fp_poly
			(pts
				(arc
					(start 2.8575 0)
					(mid -2.8575 0)
					(end 2.8575 0)
				)
			)
			(stroke
				(width 0)
				(type default)
			)
			(fill no)
			(layer "F.CrtYd")
		)
		(pad "" np_thru_hole circle
			(at 0 0)
			(size 5.207 5.207)
			(drill 5.207)
			(layers "*.Cu" "*.Mask")
			(clearance 0.381)
			(thermal_gap 0.381)
		)
		(zone
			(layers "F.Cu" "B.Cu" "In1.Cu" "In2.Cu" "In3.Cu" "In4.Cu" "In5.Cu" "In6.Cu")
			(hatch none 0.5)
			(connect_pads
				(clearance 0)
			)
			(min_thickness 0.25)
			(keepout
				(tracks not_allowed)
				(vias allowed)
				(pads allowed)
				(copperpour not_allowed)
				(footprints allowed)
			)
			(placement
				(enabled no)
				(sheetname "")
			)
			(fill
				(thermal_gap 0.5)
				(thermal_bridge_width 0.5)
				(island_removal_mode 0)
			)
			(polygon
				(pts
					(arc
						(start 81.111344 -78.299818)
						(mid 74.888344 -78.299818)
						(end 81.111344 -78.299818)
					)
				)
			)
		)
	)
	(footprint ""
		(layer "F.Cu")
		(at 26.068274 -183.06923)
		(property "Reference" "R55"
			(at -3.997198 0.128524 0)
			(unlocked yes)
			(layer "F.SilkS")
			(effects
				(font
					(size 0.7874 0.5842)
					(thickness 0.1524)
				)
				(justify left)
			)
		)
		(property "Value" ""
			(at 0 0 0)
			(layer "F.Fab")
			(effects
				(font
					(size 1.27 1.27)
				)
			)
		)
		(duplicate_pad_numbers_are_jumpers no)
		(fp_line
			(start -0.7874 -0.4064)
			(end 0.7874 -0.4064)
			(stroke
				(width 0.1524)
				(type default)
			)
			(layer "F.SilkS")
		)
		(fp_line
			(start -0.7874 0.4064)
			(end -0.7874 -0.4064)
			(stroke
				(width 0.1524)
				(type default)
			)
			(layer "F.SilkS")
		)
		(fp_line
			(start 0.7874 -0.4064)
			(end 0.7874 0.4064)
			(stroke
				(width 0.1524)
				(type default)
			)
			(layer "F.SilkS")
		)
		(fp_line
			(start 0.7874 0.4064)
			(end -0.7874 0.4064)
			(stroke
				(width 0.1524)
				(type default)
			)
			(layer "F.SilkS")
		)
		(fp_poly
			(pts
				(xy -0.508 0.2794) (xy -0.508 0.2286) (xy -0.635 0.2286) (xy -0.635 -0.254) (xy -0.5334 -0.254)
				(xy -0.5334 -0.2794) (xy 0.5334 -0.2794) (xy 0.5334 -0.254) (xy 0.635 -0.254) (xy 0.635 0.254) (xy 0.5334 0.254)
				(xy 0.5334 0.2794)
			)
			(stroke
				(width 0)
				(type default)
			)
			(fill no)
			(layer "F.CrtYd")
		)
		(pad "1" smd rect
			(at 0.40005 0)
			(size 0.4572 0.508)
			(layers "F.Cu" "F.Mask" "F.Paste")
			(net "PSU3_RESET")
		)
		(pad "2" smd rect
			(at -0.40005 0)
			(size 0.4572 0.508)
			(layers "F.Cu" "F.Mask" "F.Paste")
			(net "GND")
		)
	)
)
